(kicad_pcb
	(version 20260206)
	(generator "pcbnew")
	(generator_version "10.0")
	(general
		(thickness 1.6)
		(legacy_teardrops no)
	)
	(paper "A4")
	(title_block
		(title "9052_F0T_PDB_Converter_Brick_F_V03_1208_1600_OCP.brd")
		(comment 1 "Grand Teton / footprints 103-110 of 578")
	)
	(layers
		(0 "F.Cu" signal "TOP")
		(4 "In1.Cu" signal "GND")
		(6 "In2.Cu" signal "IN1")
		(8 "In3.Cu" signal "GND1")
		(10 "In4.Cu" signal "VCC")
		(12 "In5.Cu" signal "VCC1")
		(14 "In6.Cu" signal "GND2")
		(16 "In7.Cu" signal "IN2")
		(18 "In8.Cu" signal "GND3")
		(2 "B.Cu" signal "BOTTOM")
		(9 "F.Adhes" user "F.Adhesive")
		(11 "B.Adhes" user "B.Adhesive")
		(13 "F.Paste" user "Package Geometry/Pastemask Top")
		(15 "B.Paste" user "Package Geometry/Pastemask Bottom")
		(5 "F.SilkS" user "Ref Des/Silkscreen Top")
		(7 "B.SilkS" user "Ref Des/Silkscreen Bottom")
		(1 "F.Mask" user "Board Geometry/Soldermask Top")
		(3 "B.Mask" user "Board Geometry/Soldermask Bottom")
		(17 "Dwgs.User" user "User.Drawings")
		(19 "Cmts.User" user "User.Comments")
		(21 "Eco1.User" user "User.Eco1")
		(23 "Eco2.User" user "User.Eco2")
		(25 "Edge.Cuts" user "Board Geometry/Outline")
		(27 "Margin" user)
		(31 "F.CrtYd" user "Package Geometry/Place Bound Top")
		(29 "B.CrtYd" user "Package Geometry/Place Bound Bottom")
		(35 "F.Fab" user "Ref Des/Assembly Top")
		(33 "B.Fab" user "Ref Des/Assembly Bottom")
	)
	(footprint ""
		(layer "F.Cu")
		(at 282.321 -22.352)
		(property "Reference" "R5885"
			(at 0 0 0)
			(layer "F.SilkS")
			(hide yes)
			(effects
				(font
					(size 1.27 1.27)
				)
			)
		)
		(property "Value" ""
			(at 0 0 0)
			(layer "F.Fab")
			(effects
				(font
					(size 1.27 1.27)
				)
			)
		)
		(duplicate_pad_numbers_are_jumpers no)
		(fp_line
			(start -0.7874 -0.4064)
			(end 0.7874 -0.4064)
			(stroke
				(width 0.1524)
				(type default)
			)
			(layer "F.SilkS")
		)
		(fp_line
			(start -0.7874 0.4064)
			(end -0.7874 -0.4064)
			(stroke
				(width 0.1524)
				(type default)
			)
			(layer "F.SilkS")
		)
		(fp_line
			(start 0.7874 -0.4064)
			(end 0.7874 0.4064)
			(stroke
				(width 0.1524)
				(type default)
			)
			(layer "F.SilkS")
		)
		(fp_line
			(start 0.7874 0.4064)
			(end -0.7874 0.4064)
			(stroke
				(width 0.1524)
				(type default)
			)
			(layer "F.SilkS")
		)
		(fp_line
			(start -0.67945 -0.305054)
			(end -0.12065 -0.305054)
			(stroke
				(width 0.1)
				(type default)
			)
			(layer "F.Fab")
		)
		(fp_line
			(start -0.67945 0.3048)
			(end -0.67945 -0.305054)
			(stroke
				(width 0.1)
				(type default)
			)
			(layer "F.Fab")
		)
		(fp_line
			(start -0.12065 -0.305054)
			(end -0.12065 -0.2794)
			(stroke
				(width 0.1)
				(type default)
			)
			(layer "F.Fab")
		)
		(fp_line
			(start -0.12065 -0.2794)
			(end 0.12065 -0.2794)
			(stroke
				(width 0.1)
				(type default)
			)
			(layer "F.Fab")
		)
		(fp_line
			(start -0.12065 0.2794)
			(end -0.12065 0.3048)
			(stroke
				(width 0.1)
				(type default)
			)
			(layer "F.Fab")
		)
		(fp_line
			(start -0.12065 0.3048)
			(end -0.67945 0.3048)
			(stroke
				(width 0.1)
				(type default)
			)
			(layer "F.Fab")
		)
		(fp_line
			(start 0.120396 0.2794)
			(end -0.12065 0.2794)
			(stroke
				(width 0.1)
				(type default)
			)
			(layer "F.Fab")
		)
		(fp_line
			(start 0.120396 0.3048)
			(end 0.120396 0.2794)
			(stroke
				(width 0.1)
				(type default)
			)
			(layer "F.Fab")
		)
		(fp_line
			(start 0.12065 -0.3048)
			(end 0.67945 -0.3048)
			(stroke
				(width 0.1)
				(type default)
			)
			(layer "F.Fab")
		)
		(fp_line
			(start 0.12065 -0.2794)
			(end 0.12065 -0.3048)
			(stroke
				(width 0.1)
				(type default)
			)
			(layer "F.Fab")
		)
		(fp_line
			(start 0.67945 -0.3048)
			(end 0.67945 0.3048)
			(stroke
				(width 0.1)
				(type default)
			)
			(layer "F.Fab")
		)
		(fp_line
			(start 0.67945 0.3048)
			(end 0.120396 0.3048)
			(stroke
				(width 0.1)
				(type default)
			)
			(layer "F.Fab")
		)
		(pad "1" smd circle
			(at -0.40005 0)
			(size 0 0)
			(layers "F.Cu" "F.Mask" "F.Paste")
			(net "FM_HSC_EN_BUSBAR")
		)
		(pad "2" smd circle
			(at 0.40005 0)
			(size 0 0)
			(layers "F.Cu" "F.Mask" "F.Paste")
			(net "GND")
		)
	)
	(footprint ""
		(layer "F.Cu")
		(at 45.6946 -57.10428)
		(property "Reference" "R5901"
			(at 0 0 0)
			(layer "F.SilkS")
			(hide yes)
			(effects
				(font
					(size 1.27 1.27)
				)
			)
		)
		(property "Value" ""
			(at 0 0 0)
			(layer "F.Fab")
			(effects
				(font
					(size 1.27 1.27)
				)
			)
		)
		(duplicate_pad_numbers_are_jumpers no)
		(fp_line
			(start -0.7874 -0.4064)
			(end 0.7874 -0.4064)
			(stroke
				(width 0.1524)
				(type default)
			)
			(layer "F.SilkS")
		)
		(fp_line
			(start -0.7874 0.4064)
			(end -0.7874 -0.4064)
			(stroke
				(width 0.1524)
				(type default)
			)
			(layer "F.SilkS")
		)
		(fp_line
			(start 0.7874 -0.4064)
			(end 0.7874 0.4064)
			(stroke
				(width 0.1524)
				(type default)
			)
			(layer "F.SilkS")
		)
		(fp_line
			(start 0.7874 0.4064)
			(end -0.7874 0.4064)
			(stroke
				(width 0.1524)
				(type default)
			)
			(layer "F.SilkS")
		)
		(fp_line
			(start -0.67945 -0.305054)
			(end -0.12065 -0.305054)
			(stroke
				(width 0.1)
				(type default)
			)
			(layer "F.Fab")
		)
		(fp_line
			(start -0.67945 0.3048)
			(end -0.67945 -0.305054)
			(stroke
				(width 0.1)
				(type default)
			)
			(layer "F.Fab")
		)
		(fp_line
			(start -0.12065 -0.305054)
			(end -0.12065 -0.2794)
			(stroke
				(width 0.1)
				(type default)
			)
			(layer "F.Fab")
		)
		(fp_line
			(start -0.12065 -0.2794)
			(end 0.12065 -0.2794)
			(stroke
				(width 0.1)
				(type default)
			)
			(layer "F.Fab")
		)
		(fp_line
			(start -0.12065 0.2794)
			(end -0.12065 0.3048)
			(stroke
				(width 0.1)
				(type default)
			)
			(layer "F.Fab")
		)
		(fp_line
			(start -0.12065 0.3048)
			(end -0.67945 0.3048)
			(stroke
				(width 0.1)
				(type default)
			)
			(layer "F.Fab")
		)
		(fp_line
			(start 0.120396 0.2794)
			(end -0.12065 0.2794)
			(stroke
				(width 0.1)
				(type default)
			)
			(layer "F.Fab")
		)
		(fp_line
			(start 0.120396 0.3048)
			(end 0.120396 0.2794)
			(stroke
				(width 0.1)
				(type default)
			)
			(layer "F.Fab")
		)
		(fp_line
			(start 0.12065 -0.3048)
			(end 0.67945 -0.3048)
			(stroke
				(width 0.1)
				(type default)
			)
			(layer "F.Fab")
		)
		(fp_line
			(start 0.12065 -0.2794)
			(end 0.12065 -0.3048)
			(stroke
				(width 0.1)
				(type default)
			)
			(layer "F.Fab")
		)
		(fp_line
			(start 0.67945 -0.3048)
			(end 0.67945 0.3048)
			(stroke
				(width 0.1)
				(type default)
			)
			(layer "F.Fab")
		)
		(fp_line
			(start 0.67945 0.3048)
			(end 0.120396 0.3048)
			(stroke
				(width 0.1)
				(type default)
			)
			(layer "F.Fab")
		)
		(pad "1" smd circle
			(at -0.40005 0)
			(size 0 0)
			(layers "F.Cu" "F.Mask" "F.Paste")
			(net "P12V_HPDB_0_ISET")
		)
		(pad "2" smd circle
			(at 0.40005 0)
			(size 0 0)
			(layers "F.Cu" "F.Mask" "F.Paste")
			(net "GND")
		)
	)
	(footprint ""
		(layer "F.Cu")
		(at 229.743 -95.504 -90)
		(property "Reference" "C35"
			(at 0 0 270)
			(layer "F.SilkS")
			(hide yes)
			(effects
				(font
					(size 1.27 1.27)
				)
			)
		)
		(property "Value" ""
			(at 0 0 270)
			(layer "F.Fab")
			(effects
				(font
					(size 1.27 1.27)
				)
			)
		)
		(duplicate_pad_numbers_are_jumpers no)
		(fp_line
			(start -2.2098 0.9398)
			(end -2.2098 -0.9398)
			(stroke
				(width 0.1524)
				(type default)
			)
			(layer "F.SilkS")
		)
		(fp_line
			(start 2.2098 0.9398)
			(end -2.2098 0.9398)
			(stroke
				(width 0.1524)
				(type default)
			)
			(layer "F.SilkS")
		)
		(fp_line
			(start -2.2098 -0.9398)
			(end 2.2098 -0.9398)
			(stroke
				(width 0.1524)
				(type default)
			)
			(layer "F.SilkS")
		)
		(fp_line
			(start 2.2098 -0.9398)
			(end 2.2098 0.9398)
			(stroke
				(width 0.1524)
				(type default)
			)
			(layer "F.SilkS")
		)
		(fp_line
			(start -1.700022 0.899922)
			(end -1.700022 -0.899922)
			(stroke
				(width 0.1)
				(type default)
			)
			(layer "F.Fab")
		)
		(fp_line
			(start 1.700022 0.899922)
			(end -1.700022 0.899922)
			(stroke
				(width 0.1)
				(type default)
			)
			(layer "F.Fab")
		)
		(fp_line
			(start -1.700022 -0.899922)
			(end 1.700022 -0.899922)
			(stroke
				(width 0.1)
				(type default)
			)
			(layer "F.Fab")
		)
		(fp_line
			(start 1.700022 -0.899922)
			(end 1.700022 0.899922)
			(stroke
				(width 0.1)
				(type default)
			)
			(layer "F.Fab")
		)
		(pad "1" smd rect
			(at -1.4732 0 90)
			(size 1.1684 1.5748)
			(layers "F.Cu" "F.Mask" "F.Paste")
			(net "P52V_HS")
		)
		(pad "2" smd rect
			(at 1.4732 0 90)
			(size 1.1684 1.5748)
			(layers "F.Cu" "F.Mask" "F.Paste")
			(net "GND")
		)
	)
	(footprint ""
		(layer "F.Cu")
		(at 100.076 -61.595)
		(property "Reference" "PC57"
			(at 0 0 0)
			(layer "F.SilkS")
			(hide yes)
			(effects
				(font
					(size 1.27 1.27)
				)
			)
		)
		(property "Value" ""
			(at 0 0 0)
			(layer "F.Fab")
			(effects
				(font
					(size 1.27 1.27)
				)
			)
		)
		(duplicate_pad_numbers_are_jumpers no)
		(fp_line
			(start -0.7874 -0.4064)
			(end 0.7874 -0.4064)
			(stroke
				(width 0.1524)
				(type default)
			)
			(layer "F.SilkS")
		)
		(fp_line
			(start -0.7874 0.4064)
			(end -0.7874 -0.4064)
			(stroke
				(width 0.1524)
				(type default)
			)
			(layer "F.SilkS")
		)
		(fp_line
			(start 0.7874 -0.4064)
			(end 0.7874 0.4064)
			(stroke
				(width 0.1524)
				(type default)
			)
			(layer "F.SilkS")
		)
		(fp_line
			(start 0.7874 0.4064)
			(end -0.7874 0.4064)
			(stroke
				(width 0.1524)
				(type default)
			)
			(layer "F.SilkS")
		)
		(fp_line
			(start -0.6858 -0.3048)
			(end -0.1016 -0.3048)
			(stroke
				(width 0.1)
				(type default)
			)
			(layer "F.Fab")
		)
		(fp_line
			(start -0.6858 0.3048)
			(end -0.6858 -0.3048)
			(stroke
				(width 0.1)
				(type default)
			)
			(layer "F.Fab")
		)
		(fp_line
			(start -0.1016 -0.3048)
			(end -0.1016 -0.2794)
			(stroke
				(width 0.1)
				(type default)
			)
			(layer "F.Fab")
		)
		(fp_line
			(start -0.1016 -0.2794)
			(end 0.1016 -0.2794)
			(stroke
				(width 0.1)
				(type default)
			)
			(layer "F.Fab")
		)
		(fp_line
			(start -0.1016 0.2794)
			(end -0.1016 0.3048)
			(stroke
				(width 0.1)
				(type default)
			)
			(layer "F.Fab")
		)
		(fp_line
			(start -0.1016 0.3048)
			(end -0.6858 0.3048)
			(stroke
				(width 0.1)
				(type default)
			)
			(layer "F.Fab")
		)
		(fp_line
			(start 0.1016 -0.3048)
			(end 0.6858 -0.3048)
			(stroke
				(width 0.1)
				(type default)
			)
			(layer "F.Fab")
		)
		(fp_line
			(start 0.1016 -0.2794)
			(end 0.1016 -0.3048)
			(stroke
				(width 0.1)
				(type default)
			)
			(layer "F.Fab")
		)
		(fp_line
			(start 0.1016 0.2794)
			(end -0.1016 0.2794)
			(stroke
				(width 0.1)
				(type default)
			)
			(layer "F.Fab")
		)
		(fp_line
			(start 0.1016 0.3048)
			(end 0.1016 0.2794)
			(stroke
				(width 0.1)
				(type default)
			)
			(layer "F.Fab")
		)
		(fp_line
			(start 0.6858 -0.3048)
			(end 0.6858 0.3048)
			(stroke
				(width 0.1)
				(type default)
			)
			(layer "F.Fab")
		)
		(fp_line
			(start 0.6858 0.3048)
			(end 0.1016 0.3048)
			(stroke
				(width 0.1)
				(type default)
			)
			(layer "F.Fab")
		)
		(pad "1" smd rect
			(at -0.40005 0 180)
			(size 0.4572 0.508)
			(layers "F.Cu" "F.Mask" "F.Paste")
			(net "P12V_BRICK")
		)
		(pad "2" smd rect
			(at 0.40005 0 180)
			(size 0.4572 0.508)
			(layers "F.Cu" "F.Mask" "F.Paste")
			(net "GND")
		)
	)
	(footprint ""
		(layer "F.Cu")
		(at 270.383 -81.493868 -90)
		(property "Reference" "PR15"
			(at 0 0 270)
			(layer "F.SilkS")
			(hide yes)
			(effects
				(font
					(size 1.27 1.27)
				)
			)
		)
		(property "Value" ""
			(at 0 0 270)
			(layer "F.Fab")
			(effects
				(font
					(size 1.27 1.27)
				)
			)
		)
		(duplicate_pad_numbers_are_jumpers no)
		(fp_line
			(start -1.2954 0.5842)
			(end -1.2954 -0.5842)
			(stroke
				(width 0.1524)
				(type default)
			)
			(layer "F.SilkS")
		)
		(fp_line
			(start 1.2954 0.5842)
			(end -1.2954 0.5842)
			(stroke
				(width 0.1524)
				(type default)
			)
			(layer "F.SilkS")
		)
		(fp_line
			(start -1.2954 -0.5842)
			(end 1.2954 -0.5842)
			(stroke
				(width 0.1524)
				(type default)
			)
			(layer "F.SilkS")
		)
		(fp_line
			(start 1.2954 -0.5842)
			(end 1.2954 0.5842)
			(stroke
				(width 0.1524)
				(type default)
			)
			(layer "F.SilkS")
		)
		(fp_line
			(start -0.8636 0.4572)
			(end -0.8636 0.4318)
			(stroke
				(width 0.1)
				(type default)
			)
			(layer "F.Fab")
		)
		(fp_line
			(start 0.8636 0.4572)
			(end -0.8636 0.4572)
			(stroke
				(width 0.1)
				(type default)
			)
			(layer "F.Fab")
		)
		(fp_line
			(start -0.8636 0.4318)
			(end -0.8636 0.4064)
			(stroke
				(width 0.1)
				(type default)
			)
			(layer "F.Fab")
		)
		(fp_line
			(start -1.1938 0.4064)
			(end -1.1938 -0.406654)
			(stroke
				(width 0.1)
				(type default)
			)
			(layer "F.Fab")
		)
		(fp_line
			(start -0.8636 0.4064)
			(end -1.1938 0.4064)
			(stroke
				(width 0.1)
				(type default)
			)
			(layer "F.Fab")
		)
		(fp_line
			(start 0.8636 0.4064)
			(end 0.8636 0.4572)
			(stroke
				(width 0.1)
				(type default)
			)
			(layer "F.Fab")
		)
		(fp_line
			(start 1.1938 0.4064)
			(end 0.8636 0.4064)
			(stroke
				(width 0.1)
				(type default)
			)
			(layer "F.Fab")
		)
		(fp_line
			(start -1.1938 -0.406654)
			(end -0.8636 -0.406654)
			(stroke
				(width 0.1)
				(type default)
			)
			(layer "F.Fab")
		)
		(fp_line
			(start -0.8636 -0.406654)
			(end -0.8636 -0.4572)
			(stroke
				(width 0.1)
				(type default)
			)
			(layer "F.Fab")
		)
		(fp_line
			(start 0.8636 -0.406654)
			(end 1.1938 -0.406654)
			(stroke
				(width 0.1)
				(type default)
			)
			(layer "F.Fab")
		)
		(fp_line
			(start 1.1938 -0.406654)
			(end 1.1938 0.4064)
			(stroke
				(width 0.1)
				(type default)
			)
			(layer "F.Fab")
		)
		(fp_line
			(start -0.8636 -0.4572)
			(end 0.8636 -0.4572)
			(stroke
				(width 0.1)
				(type default)
			)
			(layer "F.Fab")
		)
		(fp_line
			(start 0.8636 -0.4572)
			(end 0.8636 -0.406654)
			(stroke
				(width 0.1)
				(type default)
			)
			(layer "F.Fab")
		)
		(pad "1" smd rect
			(at -0.7366 0 180)
			(size 0.7112 0.8128)
			(layers "F.Cu" "F.Mask" "F.Paste")
			(net "P52V_HS1_GATE2_R")
		)
		(pad "2" smd rect
			(at 0.7366 0 180)
			(size 0.7112 0.8128)
			(layers "F.Cu" "F.Mask" "F.Paste")
			(net "P52V_HS1_GATE5")
		)
	)
	(footprint ""
		(layer "F.Cu")
		(at 260.236716 -47.946818)
		(property "Reference" "PR25"
			(at 0 0 0)
			(layer "F.SilkS")
			(hide yes)
			(effects
				(font
					(size 1.27 1.27)
				)
			)
		)
		(property "Value" ""
			(at 0 0 0)
			(layer "F.Fab")
			(effects
				(font
					(size 1.27 1.27)
				)
			)
		)
		(duplicate_pad_numbers_are_jumpers no)
		(fp_line
			(start -1.651 -0.8382)
			(end 1.651 -0.8382)
			(stroke
				(width 0.1524)
				(type default)
			)
			(layer "F.SilkS")
		)
		(fp_line
			(start -1.651 0.8382)
			(end -1.651 -0.8382)
			(stroke
				(width 0.1524)
				(type default)
			)
			(layer "F.SilkS")
		)
		(fp_line
			(start 1.651 -0.8382)
			(end 1.651 0.8382)
			(stroke
				(width 0.1524)
				(type default)
			)
			(layer "F.SilkS")
		)
		(fp_line
			(start 1.651 0.8382)
			(end -1.651 0.8382)
			(stroke
				(width 0.1524)
				(type default)
			)
			(layer "F.SilkS")
		)
		(fp_line
			(start -1.559814 -0.7366)
			(end -1.559814 0.7366)
			(stroke
				(width 0.1)
				(type default)
			)
			(layer "F.Fab")
		)
		(fp_line
			(start -1.559814 0.7366)
			(end -1.524 0.7366)
			(stroke
				(width 0.1)
				(type default)
			)
			(layer "F.Fab")
		)
		(fp_line
			(start -1.524 -0.7366)
			(end -1.559814 -0.7366)
			(stroke
				(width 0.1)
				(type default)
			)
			(layer "F.Fab")
		)
		(fp_line
			(start -1.524 0.7366)
			(end 1.524 0.7366)
			(stroke
				(width 0.1)
				(type default)
			)
			(layer "F.Fab")
		)
		(fp_line
			(start 1.524 -0.7366)
			(end -1.524 -0.7366)
			(stroke
				(width 0.1)
				(type default)
			)
			(layer "F.Fab")
		)
		(fp_line
			(start 1.524 0.7366)
			(end 1.560576 0.7366)
			(stroke
				(width 0.1)
				(type default)
			)
			(layer "F.Fab")
		)
		(fp_line
			(start 1.560576 -0.7366)
			(end 1.524 -0.7366)
			(stroke
				(width 0.1)
				(type default)
			)
			(layer "F.Fab")
		)
		(fp_line
			(start 1.560576 0.7366)
			(end 1.560576 -0.7366)
			(stroke
				(width 0.1)
				(type default)
			)
			(layer "F.Fab")
		)
		(pad "1" smd rect
			(at -0.94996 0 180)
			(size 1.1176 1.3716)
			(layers "F.Cu" "F.Mask" "F.Paste")
			(net "P52V_HS")
		)
		(pad "2" smd rect
			(at 0.94996 0 180)
			(size 1.1176 1.3716)
			(layers "F.Cu" "F.Mask" "F.Paste")
			(net "P52V_HS1_VDSFB")
		)
	)
	(footprint ""
		(layer "F.Cu")
		(at 198.115174 -60.96)
		(property "Reference" "PC135"
			(at -2.027174 -3.65633 0)
			(unlocked yes)
			(layer "F.SilkS")
			(effects
				(font
					(size 0.7874 0.5842)
					(thickness 0.1524)
				)
				(justify left)
			)
		)
		(property "Value" ""
			(at 0 0 0)
			(layer "F.Fab")
			(effects
				(font
					(size 1.27 1.27)
				)
			)
		)
		(duplicate_pad_numbers_are_jumpers no)
		(fp_line
			(start 5.2578 2.499868)
			(end -5.2578 2.499868)
			(stroke
				(width 0.1524)
				(type default)
			)
			(layer "F.SilkS")
		)
		(fp_circle
			(center 0 2.499868)
			(end 5.2578 2.499868)
			(stroke
				(width 0.1524)
				(type default)
			)
			(fill no)
			(layer "F.SilkS")
		)
		(fp_poly
			(pts
				(arc
					(start 5.2578 2.499868)
					(mid 0 7.757922)
					(end -5.2578 2.499868)
				)
			)
			(stroke
				(width 0)
				(type default)
			)
			(fill yes)
			(layer "F.SilkS")
		)
		(fp_circle
			(center 0 2.499868)
			(end 5.2578 2.499868)
			(stroke
				(width 0.1)
				(type default)
			)
			(fill no)
			(layer "F.Fab")
		)
		(pad "1" thru_hole rect
			(at 0 0 270)
			(size 1.524 1.524)
			(drill 1.016)
			(layers "*.Cu" "*.Mask")
			(remove_unused_layers no)
			(net "P12V_BRICK")
			(clearance 0)
			(padstack
				(mode front_inner_back)
				(layer "Inner"
					(shape circle)
					(size 1.524 1.524)
					(clearance 0)
				)
				(layer "B.Cu"
					(shape rect)
					(size 1.524 1.524)
					(clearance 0)
				)
			)
		)
		(pad "2" thru_hole circle
			(at 0 4.99999 270)
			(size 1.524 1.524)
			(drill 1.016)
			(layers "*.Cu" "*.Mask")
			(remove_unused_layers no)
			(net "GND")
			(clearance 0)
		)
	)
	(footprint ""
		(layer "F.Cu")
		(at 158.115 -60.96)
		(property "Reference" "PC42"
			(at -1.397 -3.52933 0)
			(unlocked yes)
			(layer "F.SilkS")
			(effects
				(font
					(size 0.7874 0.5842)
					(thickness 0.1524)
				)
				(justify left)
			)
		)
		(property "Value" ""
			(at 0 0 0)
			(layer "F.Fab")
			(effects
				(font
					(size 1.27 1.27)
				)
			)
		)
		(duplicate_pad_numbers_are_jumpers no)
		(fp_line
			(start 5.2578 2.499868)
			(end -5.2578 2.499868)
			(stroke
				(width 0.1524)
				(type default)
			)
			(layer "F.SilkS")
		)
		(fp_circle
			(center 0 2.499868)
			(end 5.2578 2.499868)
			(stroke
				(width 0.1524)
				(type default)
			)
			(fill no)
			(layer "F.SilkS")
		)
		(fp_poly
			(pts
				(arc
					(start 5.2578 2.499868)
					(mid 0 7.757922)
					(end -5.2578 2.499868)
				)
			)
			(stroke
				(width 0)
				(type default)
			)
			(fill yes)
			(layer "F.SilkS")
		)
		(fp_circle
			(center 0 2.499868)
			(end 5.2578 2.499868)
			(stroke
				(width 0.1)
				(type default)
			)
			(fill no)
			(layer "F.Fab")
		)
		(pad "1" thru_hole rect
			(at 0 0 270)
			(size 1.524 1.524)
			(drill 1.016)
			(layers "*.Cu" "*.Mask")
			(remove_unused_layers no)
			(net "P12V_BRICK")
			(clearance 0)
			(padstack
				(mode front_inner_back)
				(layer "Inner"
					(shape circle)
					(size 1.524 1.524)
					(clearance 0)
				)
				(layer "B.Cu"
					(shape rect)
					(size 1.524 1.524)
					(clearance 0)
				)
			)
		)
		(pad "2" thru_hole circle
			(at 0 4.99999 270)
			(size 1.524 1.524)
			(drill 1.016)
			(layers "*.Cu" "*.Mask")
			(remove_unused_layers no)
			(net "GND")
			(clearance 0)
		)
	)
)
